(kicad_pcb
	(version 20260206)
	(generator "pcbnew")
	(generator_version "10.0")
	(general
		(thickness 1.6)
		(legacy_teardrops no)
	)
	(paper "A4")
	(title_block
		(title "03242023_DA0F0TMBIJ0_F0T_Motherboard_J_brd_V01_OCP.brd")
		(comment 1 "Grand Teton / footprints 690-695 of 6105")
	)
	(layers
		(0 "F.Cu" signal "TOP")
		(4 "In1.Cu" signal "GND")
		(6 "In2.Cu" signal "IN1")
		(8 "In3.Cu" signal "GND1")
		(10 "In4.Cu" signal "IN2")
		(12 "In5.Cu" signal "GND2")
		(14 "In6.Cu" signal "IN3")
		(16 "In7.Cu" signal "GND3")
		(18 "In8.Cu" signal "VCC")
		(20 "In9.Cu" signal "VCC1")
		(22 "In10.Cu" signal "GND4")
		(24 "In11.Cu" signal "IN4")
		(26 "In12.Cu" signal "GND5")
		(28 "In13.Cu" signal "IN5")
		(30 "In14.Cu" signal "GND6")
		(32 "In15.Cu" signal "IN6")
		(34 "In16.Cu" signal "GND7")
		(2 "B.Cu" signal "BOTTOM")
		(9 "F.Adhes" user "F.Adhesive")
		(11 "B.Adhes" user "B.Adhesive")
		(13 "F.Paste" user "Package Geometry/Pastemask Top")
		(15 "B.Paste" user "Package Geometry/Pastemask Bottom")
		(5 "F.SilkS" user "Ref Des/Silkscreen Top")
		(7 "B.SilkS" user "Ref Des/Silkscreen Bottom")
		(1 "F.Mask" user "Board Geometry/Soldermask Top")
		(3 "B.Mask" user "Board Geometry/Soldermask Bottom")
		(17 "Dwgs.User" user "User.Drawings")
		(19 "Cmts.User" user "User.Comments")
		(21 "Eco1.User" user "User.Eco1")
		(23 "Eco2.User" user "User.Eco2")
		(25 "Edge.Cuts" user "Board Geometry/Outline")
		(27 "Margin" user)
		(31 "F.CrtYd" user "Package Geometry/Place Bound Top")
		(29 "B.CrtYd" user "Package Geometry/Place Bound Bottom")
		(35 "F.Fab" user "Ref Des/Assembly Top")
		(33 "B.Fab" user "Ref Des/Assembly Bottom")
	)
	(footprint ""
		(layer "F.Cu")
		(at 235.899706 -81.699862 180)
		(property "Reference" "H115"
			(at -3.231388 -9.86282 0)
			(unlocked yes)
			(layer "F.SilkS")
			(effects
				(font
					(size 0.7874 0.5842)
					(thickness 0.1524)
				)
				(justify left)
			)
		)
		(property "Value" ""
			(at 0 0 180)
			(layer "F.Fab")
			(effects
				(font
					(size 1.27 1.27)
				)
			)
		)
		(duplicate_pad_numbers_are_jumpers no)
		(fp_circle
			(center 0 0)
			(end -7.999984 0)
			(stroke
				(width 0.1524)
				(type default)
			)
			(fill no)
			(layer "F.SilkS")
		)
		(fp_arc
			(start 1.378458 7.88035)
			(mid -5.146459 6.124845)
			(end -7.999984 0)
			(stroke
				(width 0.1524)
				(type default)
			)
			(layer "B.SilkS")
		)
		(fp_arc
			(start -0.846328 -7.955026)
			(mid 6.678862 -4.403794)
			(end 6.978396 3.911854)
			(stroke
				(width 0.1524)
				(type default)
			)
			(layer "B.SilkS")
		)
		(fp_arc
			(start -7.999984 0)
			(mid -7.68431 -2.225377)
			(end -6.761988 -4.275074)
			(stroke
				(width 0.1524)
				(type default)
			)
			(layer "B.SilkS")
		)
		(fp_circle
			(center 0 0)
			(end -7.999984 0)
			(stroke
				(width 0.1)
				(type default)
			)
			(fill no)
			(layer "B.Fab")
		)
		(fp_circle
			(center 0 0)
			(end -7.999984 0)
			(stroke
				(width 0.1)
				(type default)
			)
			(fill no)
			(layer "F.Fab")
		)
		(pad "" np_thru_hole oval
			(at 0 0 90)
			(size 5.08 6.477)
			(drill oval 5.08 6.477)
			(layers "*.Cu" "*.Mask")
			(clearance 0.381)
			(thermal_gap 0.381)
		)
		(pad "2" thru_hole circle
			(at 4.38023 0 180)
			(size 0.762 0.762)
			(drill 0.5588)
			(layers "*.Cu" "*.Mask")
			(remove_unused_layers no)
			(net "GND")
			(clearance 0.1524)
			(thermal_gap 0.1524)
		)
		(pad "3" thru_hole circle
			(at 3.097276 -3.097276 180)
			(size 0.762 0.762)
			(drill 0.5588)
			(layers "*.Cu" "*.Mask")
			(remove_unused_layers no)
			(net "GND")
			(clearance 0.1524)
			(thermal_gap 0.1524)
		)
		(pad "4" thru_hole circle
			(at 0 -4.38023 180)
			(size 0.762 0.762)
			(drill 0.5588)
			(layers "*.Cu" "*.Mask")
			(remove_unused_layers no)
			(net "GND")
			(clearance 0.1524)
			(thermal_gap 0.1524)
		)
		(pad "5" thru_hole circle
			(at -3.097276 -3.097276 180)
			(size 0.762 0.762)
			(drill 0.5588)
			(layers "*.Cu" "*.Mask")
			(remove_unused_layers no)
			(net "GND")
			(clearance 0.1524)
			(thermal_gap 0.1524)
		)
		(pad "6" thru_hole circle
			(at -4.38023 0 180)
			(size 0.762 0.762)
			(drill 0.5588)
			(layers "*.Cu" "*.Mask")
			(remove_unused_layers no)
			(net "GND")
			(clearance 0.1524)
			(thermal_gap 0.1524)
		)
		(pad "7" thru_hole circle
			(at -3.097276 3.097276 180)
			(size 0.762 0.762)
			(drill 0.5588)
			(layers "*.Cu" "*.Mask")
			(remove_unused_layers no)
			(net "GND")
			(clearance 0.1524)
			(thermal_gap 0.1524)
		)
		(pad "8" thru_hole circle
			(at 0 4.38023 180)
			(size 0.762 0.762)
			(drill 0.5588)
			(layers "*.Cu" "*.Mask")
			(remove_unused_layers no)
			(net "GND")
			(clearance 0.1524)
			(thermal_gap 0.1524)
		)
		(pad "9" thru_hole circle
			(at 3.097276 3.097276 180)
			(size 0.762 0.762)
			(drill 0.5588)
			(layers "*.Cu" "*.Mask")
			(remove_unused_layers no)
			(net "GND")
			(clearance 0.1524)
			(thermal_gap 0.1524)
		)
		(zone
			(layer "F.Cu")
			(hatch none 0.5)
			(connect_pads
				(clearance 0)
			)
			(min_thickness 0.25)
			(keepout
				(tracks not_allowed)
				(vias allowed)
				(pads allowed)
				(copperpour not_allowed)
				(footprints allowed)
			)
			(placement
				(enabled no)
				(sheetname "")
			)
			(fill
				(thermal_gap 0.5)
				(thermal_bridge_width 0.5)
				(island_removal_mode 0)
			)
			(polygon
				(pts
					(arc
						(start 230.391716 -81.699862)
						(mid 232.004969 -85.594599)
						(end 235.899706 -87.207852)
					)
					(arc
						(start 235.899706 -86.725252)
						(mid 230.874316 -81.699862)
						(end 235.899706 -76.674472)
					)
					(arc
						(start 235.899706 -76.191872)
						(mid 232.004969 -77.805125)
						(end 230.391716 -81.699862)
					)
				)
			)
		)
		(zone
			(layer "F.Cu")
			(hatch none 0.5)
			(connect_pads
				(clearance 0)
			)
			(min_thickness 0.25)
			(keepout
				(tracks not_allowed)
				(vias allowed)
				(pads allowed)
				(copperpour not_allowed)
				(footprints allowed)
			)
			(placement
				(enabled no)
				(sheetname "")
			)
			(fill
				(thermal_gap 0.5)
				(thermal_bridge_width 0.5)
				(island_removal_mode 0)
			)
			(polygon
				(pts
					(arc
						(start 241.407696 -81.699862)
						(mid 239.794443 -85.594599)
						(end 235.899706 -87.207852)
					)
					(arc
						(start 235.899706 -86.725252)
						(mid 240.925096 -81.699862)
						(end 235.899706 -76.674472)
					)
					(arc
						(start 235.899706 -76.191872)
						(mid 239.794443 -77.805125)
						(end 241.407696 -81.699862)
					)
				)
			)
		)
		(zone
			(layers "F.Cu" "B.Cu" "In1.Cu" "In2.Cu" "In3.Cu" "In4.Cu" "In5.Cu" "In6.Cu"
				"In7.Cu" "In8.Cu" "In9.Cu" "In10.Cu" "In11.Cu" "In12.Cu" "In13.Cu" "In14.Cu"
				"In15.Cu" "In16.Cu"
			)
			(hatch none 0.5)
			(connect_pads
				(clearance 0)
			)
			(min_thickness 0.25)
			(keepout
				(tracks not_allowed)
				(vias allowed)
				(pads allowed)
				(copperpour not_allowed)
				(footprints allowed)
			)
			(placement
				(enabled no)
				(sheetname "")
			)
			(fill
				(thermal_gap 0.5)
				(thermal_bridge_width 0.5)
				(island_removal_mode 0)
			)
			(polygon
				(pts
					(arc
						(start 233.715306 -78.641956)
						(mid 235.899706 -85.457839)
						(end 238.084106 -78.641956)
					)
				)
			)
		)
		(zone
			(layer "B.Cu")
			(hatch none 0.5)
			(connect_pads
				(clearance 0)
			)
			(min_thickness 0.25)
			(keepout
				(tracks not_allowed)
				(vias allowed)
				(pads allowed)
				(copperpour not_allowed)
				(footprints allowed)
			)
			(placement
				(enabled no)
				(sheetname "")
			)
			(fill
				(thermal_gap 0.5)
				(thermal_bridge_width 0.5)
				(island_removal_mode 0)
			)
			(polygon
				(pts
					(arc
						(start 235.899706 -89.699846)
						(mid 227.899722 -81.699862)
						(end 235.899706 -73.699878)
					)
					(arc
						(start 235.899706 -76.445872)
						(mid 232.184574 -77.98473)
						(end 230.645716 -81.699862)
					)
					(arc
						(start 230.645716 -81.699862)
						(mid 232.184574 -85.414994)
						(end 235.899706 -86.953852)
					)
				)
			)
		)
		(zone
			(layer "B.Cu")
			(hatch none 0.5)
			(connect_pads
				(clearance 0)
			)
			(min_thickness 0.25)
			(keepout
				(tracks not_allowed)
				(vias allowed)
				(pads allowed)
				(copperpour not_allowed)
				(footprints allowed)
			)
			(placement
				(enabled no)
				(sheetname "")
			)
			(fill
				(thermal_gap 0.5)
				(thermal_bridge_width 0.5)
				(island_removal_mode 0)
			)
			(polygon
				(pts
					(arc
						(start 235.899706 -89.699846)
						(mid 243.89969 -81.699862)
						(end 235.899706 -73.699878)
					)
					(arc
						(start 235.899706 -76.445872)
						(mid 239.614838 -77.98473)
						(end 241.153696 -81.699862)
					)
					(arc
						(start 241.153696 -81.699862)
						(mid 239.614838 -85.414994)
						(end 235.899706 -86.953852)
					)
				)
			)
		)
	)
	(footprint ""
		(layer "F.Cu")
		(at 430.827434 -98.175064 180)
		(property "Reference" "R3645"
			(at 0 0 180)
			(layer "F.SilkS")
			(hide yes)
			(effects
				(font
					(size 1.27 1.27)
				)
			)
		)
		(property "Value" ""
			(at 0 0 180)
			(layer "F.Fab")
			(effects
				(font
					(size 1.27 1.27)
				)
			)
		)
		(duplicate_pad_numbers_are_jumpers no)
		(fp_line
			(start 4.0386 1.7526)
			(end -4.0386 1.7526)
			(stroke
				(width 0.1524)
				(type default)
			)
			(layer "F.SilkS")
		)
		(fp_line
			(start 4.0386 -1.7526)
			(end 4.0386 1.7526)
			(stroke
				(width 0.1524)
				(type default)
			)
			(layer "F.SilkS")
		)
		(fp_line
			(start -4.0386 1.7526)
			(end -4.0386 -1.7526)
			(stroke
				(width 0.1524)
				(type default)
			)
			(layer "F.SilkS")
		)
		(fp_line
			(start -4.0386 -1.7526)
			(end 4.0386 -1.7526)
			(stroke
				(width 0.1524)
				(type default)
			)
			(layer "F.SilkS")
		)
		(fp_line
			(start 4.0386 1.7526)
			(end -4.0386 1.7526)
			(stroke
				(width 0.1)
				(type default)
			)
			(layer "F.Fab")
		)
		(fp_line
			(start 4.0386 -1.7526)
			(end 4.0386 1.7526)
			(stroke
				(width 0.1)
				(type default)
			)
			(layer "F.Fab")
		)
		(fp_line
			(start -4.0386 1.7526)
			(end -4.0386 -1.7526)
			(stroke
				(width 0.1)
				(type default)
			)
			(layer "F.Fab")
		)
		(fp_line
			(start -4.0386 -1.7526)
			(end 4.0386 -1.7526)
			(stroke
				(width 0.1)
				(type default)
			)
			(layer "F.Fab")
		)
		(pad "1" smd rect
			(at -3.1115 0 180)
			(size 1.524 3.2004)
			(layers "F.Cu" "F.Mask" "F.Paste")
			(net "P3V3_OCP_SFF")
		)
		(pad "2" smd rect
			(at 3.1115 0 180)
			(size 1.524 3.2004)
			(layers "F.Cu" "F.Mask" "F.Paste")
			(net "P3V3_OCP_SFF_R")
		)
	)
	(footprint ""
		(layer "F.Cu")
		(at 69.923406 -166.634922)
		(property "Reference" "PC385"
			(at 0 0 0)
			(layer "F.SilkS")
			(hide yes)
			(effects
				(font
					(size 1.27 1.27)
				)
			)
		)
		(property "Value" ""
			(at 0 0 0)
			(layer "F.Fab")
			(effects
				(font
					(size 1.27 1.27)
				)
			)
		)
		(duplicate_pad_numbers_are_jumpers no)
		(fp_line
			(start 2.750058 0.999998)
			(end -2.750058 0.999998)
			(stroke
				(width 0.1524)
				(type default)
			)
			(layer "F.SilkS")
		)
		(fp_circle
			(center 0 0.999998)
			(end 2.750058 0.999998)
			(stroke
				(width 0.1524)
				(type default)
			)
			(fill no)
			(layer "F.SilkS")
		)
		(fp_poly
			(pts
				(arc
					(start 2.750058 0.999998)
					(mid 0 3.750056)
					(end -2.750058 0.999998)
				)
			)
			(stroke
				(width 0)
				(type default)
			)
			(fill yes)
			(layer "F.SilkS")
		)
		(fp_circle
			(center 0 0.999998)
			(end 2.750058 0.999998)
			(stroke
				(width 0.1)
				(type default)
			)
			(fill no)
			(layer "F.Fab")
		)
		(pad "1" thru_hole rect
			(at 0 0)
			(size 1.5748 1.5748)
			(drill 1.0668)
			(layers "*.Cu" "*.Mask")
			(remove_unused_layers no)
			(net "PVCCD_HV_CPU1")
			(clearance 0)
			(padstack
				(mode front_inner_back)
				(layer "Inner"
					(shape circle)
					(size 1.5748 1.5748)
					(clearance 0)
				)
				(layer "B.Cu"
					(shape rect)
					(size 1.5748 1.5748)
					(clearance 0)
				)
			)
		)
		(pad "2" thru_hole circle
			(at 0 1.999996)
			(size 1.5748 1.5748)
			(drill 1.0668)
			(layers "*.Cu" "*.Mask")
			(remove_unused_layers no)
			(net "GND")
			(clearance 0)
		)
	)
	(footprint ""
		(layer "F.Cu")
		(at 426.6819 -109.644688 90)
		(property "Reference" "PC2081"
			(at 0 0 90)
			(layer "F.SilkS")
			(hide yes)
			(effects
				(font
					(size 1.27 1.27)
				)
			)
		)
		(property "Value" ""
			(at 0 0 90)
			(layer "F.Fab")
			(effects
				(font
					(size 1.27 1.27)
				)
			)
		)
		(duplicate_pad_numbers_are_jumpers no)
		(fp_line
			(start 1.524 -0.762)
			(end 1.524 0.762)
			(stroke
				(width 0.1524)
				(type default)
			)
			(layer "F.SilkS")
		)
		(fp_line
			(start -1.524 -0.762)
			(end 1.524 -0.762)
			(stroke
				(width 0.1524)
				(type default)
			)
			(layer "F.SilkS")
		)
		(fp_line
			(start 1.524 0.762)
			(end -1.524 0.762)
			(stroke
				(width 0.1524)
				(type default)
			)
			(layer "F.SilkS")
		)
		(fp_line
			(start -1.524 0.762)
			(end -1.524 -0.762)
			(stroke
				(width 0.1524)
				(type default)
			)
			(layer "F.SilkS")
		)
		(fp_line
			(start 1.1049 -0.724916)
			(end -1.1049 -0.724916)
			(stroke
				(width 0.1)
				(type default)
			)
			(layer "F.Fab")
		)
		(fp_line
			(start -1.1049 -0.724916)
			(end -1.1049 0.724916)
			(stroke
				(width 0.1)
				(type default)
			)
			(layer "F.Fab")
		)
		(fp_line
			(start 1.1049 0.724916)
			(end 1.1049 -0.724916)
			(stroke
				(width 0.1)
				(type default)
			)
			(layer "F.Fab")
		)
		(fp_line
			(start -1.1049 0.724916)
			(end 1.1049 0.724916)
			(stroke
				(width 0.1)
				(type default)
			)
			(layer "F.Fab")
		)
		(pad "1" smd rect
			(at -0.889 0 270)
			(size 1.016 1.27)
			(layers "F.Cu" "F.Mask" "F.Paste")
			(net "P3V3_OCP_SFF_R")
		)
		(pad "2" smd rect
			(at 0.889 0 270)
			(size 1.016 1.27)
			(layers "F.Cu" "F.Mask" "F.Paste")
			(net "GND")
		)
	)
	(footprint ""
		(layer "F.Cu")
		(at 105.2957 -255.0541 90)
		(property "Reference" "C246"
			(at 0 0 90)
			(layer "F.SilkS")
			(hide yes)
			(effects
				(font
					(size 1.27 1.27)
				)
			)
		)
		(property "Value" ""
			(at 0 0 90)
			(layer "F.Fab")
			(effects
				(font
					(size 1.27 1.27)
				)
			)
		)
		(duplicate_pad_numbers_are_jumpers no)
		(fp_line
			(start 0.7874 -0.4064)
			(end 0.7874 0.4064)
			(stroke
				(width 0.1524)
				(type default)
			)
			(layer "F.SilkS")
		)
		(fp_line
			(start -0.7874 -0.4064)
			(end 0.7874 -0.4064)
			(stroke
				(width 0.1524)
				(type default)
			)
			(layer "F.SilkS")
		)
		(fp_line
			(start 0.7874 0.4064)
			(end -0.7874 0.4064)
			(stroke
				(width 0.1524)
				(type default)
			)
			(layer "F.SilkS")
		)
		(fp_line
			(start -0.7874 0.4064)
			(end -0.7874 -0.4064)
			(stroke
				(width 0.1524)
				(type default)
			)
			(layer "F.SilkS")
		)
		(fp_line
			(start -0.12065 -0.305054)
			(end -0.12065 -0.2794)
			(stroke
				(width 0.1)
				(type default)
			)
			(layer "F.Fab")
		)
		(fp_line
			(start -0.67945 -0.305054)
			(end -0.12065 -0.305054)
			(stroke
				(width 0.1)
				(type default)
			)
			(layer "F.Fab")
		)
		(fp_line
			(start 0.67945 -0.3048)
			(end 0.67945 0.3048)
			(stroke
				(width 0.1)
				(type default)
			)
			(layer "F.Fab")
		)
		(fp_line
			(start 0.12065 -0.3048)
			(end 0.67945 -0.3048)
			(stroke
				(width 0.1)
				(type default)
			)
			(layer "F.Fab")
		)
		(fp_line
			(start 0.12065 -0.2794)
			(end 0.12065 -0.3048)
			(stroke
				(width 0.1)
				(type default)
			)
			(layer "F.Fab")
		)
		(fp_line
			(start -0.12065 -0.2794)
			(end 0.12065 -0.2794)
			(stroke
				(width 0.1)
				(type default)
			)
			(layer "F.Fab")
		)
		(fp_line
			(start 0.120396 0.2794)
			(end -0.12065 0.2794)
			(stroke
				(width 0.1)
				(type default)
			)
			(layer "F.Fab")
		)
		(fp_line
			(start -0.12065 0.2794)
			(end -0.12065 0.3048)
			(stroke
				(width 0.1)
				(type default)
			)
			(layer "F.Fab")
		)
		(fp_line
			(start 0.67945 0.3048)
			(end 0.120396 0.3048)
			(stroke
				(width 0.1)
				(type default)
			)
			(layer "F.Fab")
		)
		(fp_line
			(start 0.120396 0.3048)
			(end 0.120396 0.2794)
			(stroke
				(width 0.1)
				(type default)
			)
			(layer "F.Fab")
		)
		(fp_line
			(start -0.12065 0.3048)
			(end -0.67945 0.3048)
			(stroke
				(width 0.1)
				(type default)
			)
			(layer "F.Fab")
		)
		(fp_line
			(start -0.67945 0.3048)
			(end -0.67945 -0.305054)
			(stroke
				(width 0.1)
				(type default)
			)
			(layer "F.Fab")
		)
		(pad "1" smd circle
			(at -0.40005 0 90)
			(size 0 0)
			(layers "F.Cu" "F.Mask" "F.Paste")
			(net "PVCCIN_CPU1")
		)
		(pad "2" smd circle
			(at 0.40005 0 90)
			(size 0 0)
			(layers "F.Cu" "F.Mask" "F.Paste")
			(net "GND")
		)
	)
	(footprint ""
		(layer "F.Cu")
		(at 128.9685 -74.824082 -90)
		(property "Reference" "R1345"
			(at 0 0 270)
			(layer "F.SilkS")
			(hide yes)
			(effects
				(font
					(size 1.27 1.27)
				)
			)
		)
		(property "Value" ""
			(at 0 0 270)
			(layer "F.Fab")
			(effects
				(font
					(size 1.27 1.27)
				)
			)
		)
		(duplicate_pad_numbers_are_jumpers no)
		(fp_line
			(start -0.7874 0.4064)
			(end -0.7874 -0.4064)
			(stroke
				(width 0.1524)
				(type default)
			)
			(layer "F.SilkS")
		)
		(fp_line
			(start 0.7874 0.4064)
			(end -0.7874 0.4064)
			(stroke
				(width 0.1524)
				(type default)
			)
			(layer "F.SilkS")
		)
		(fp_line
			(start -0.7874 -0.4064)
			(end 0.7874 -0.4064)
			(stroke
				(width 0.1524)
				(type default)
			)
			(layer "F.SilkS")
		)
		(fp_line
			(start 0.7874 -0.4064)
			(end 0.7874 0.4064)
			(stroke
				(width 0.1524)
				(type default)
			)
			(layer "F.SilkS")
		)
		(fp_line
			(start -0.67945 0.3048)
			(end -0.67945 -0.305054)
			(stroke
				(width 0.1)
				(type default)
			)
			(layer "F.Fab")
		)
		(fp_line
			(start -0.12065 0.3048)
			(end -0.67945 0.3048)
			(stroke
				(width 0.1)
				(type default)
			)
			(layer "F.Fab")
		)
		(fp_line
			(start 0.120396 0.3048)
			(end 0.120396 0.2794)
			(stroke
				(width 0.1)
				(type default)
			)
			(layer "F.Fab")
		)
		(fp_line
			(start 0.67945 0.3048)
			(end 0.120396 0.3048)
			(stroke
				(width 0.1)
				(type default)
			)
			(layer "F.Fab")
		)
		(fp_line
			(start -0.12065 0.2794)
			(end -0.12065 0.3048)
			(stroke
				(width 0.1)
				(type default)
			)
			(layer "F.Fab")
		)
		(fp_line
			(start 0.120396 0.2794)
			(end -0.12065 0.2794)
			(stroke
				(width 0.1)
				(type default)
			)
			(layer "F.Fab")
		)
		(fp_line
			(start -0.12065 -0.2794)
			(end 0.12065 -0.2794)
			(stroke
				(width 0.1)
				(type default)
			)
			(layer "F.Fab")
		)
		(fp_line
			(start 0.12065 -0.2794)
			(end 0.12065 -0.3048)
			(stroke
				(width 0.1)
				(type default)
			)
			(layer "F.Fab")
		)
		(fp_line
			(start 0.12065 -0.3048)
			(end 0.67945 -0.3048)
			(stroke
				(width 0.1)
				(type default)
			)
			(layer "F.Fab")
		)
		(fp_line
			(start 0.67945 -0.3048)
			(end 0.67945 0.3048)
			(stroke
				(width 0.1)
				(type default)
			)
			(layer "F.Fab")
		)
		(fp_line
			(start -0.67945 -0.305054)
			(end -0.12065 -0.305054)
			(stroke
				(width 0.1)
				(type default)
			)
			(layer "F.Fab")
		)
		(fp_line
			(start -0.12065 -0.305054)
			(end -0.12065 -0.2794)
			(stroke
				(width 0.1)
				(type default)
			)
			(layer "F.Fab")
		)
		(pad "1" smd circle
			(at -0.40005 0 270)
			(size 0 0)
			(layers "F.Cu" "F.Mask" "F.Paste")
			(net "JTAG_BMC_DBP_TDI_R")
		)
		(pad "2" smd circle
			(at 0.40005 0 270)
			(size 0 0)
			(layers "F.Cu" "F.Mask" "F.Paste")
			(net "JTAG_BMC_DBP_TDI")
		)
	)
)
